# T6G (Grand Teton) — schematic parts with pin connectivity, parts 8081–8081 of 8303; source: Cadence DE-HDL packaged netlist (pstxprt.dat, pstxnet.dat, pstchip.dat)

U25  GENOA_SP5  SOCKET6096_13568-001 IO  pkg SOCKET6096_93-4X120-45XA  page 10  (pins 1009-1344 of 6096)
  AP18  MJA_CHECK5  BI  = M_J_CPU0_SA_CB<5>
  AP19  VSS_AP19  POWER  = GND
  AP20  MIA_CHECK6  BI  = M_I_CPU0_SA_CB<6>
  AP21  MIA_CHECK5  BI  = M_I_CPU0_SA_CB<5>
  AP22  VSS_AP22  POWER  = GND
  AP23  VDDCR_CPU0_AP23  POWER  = PVDDCR_CPU0_P0
  AP24  VDDCR_CPU0_AP24  POWER  = PVDDCR_CPU0_P0
  AP25  VSS_AP25  POWER  = GND
  AP26  VDDCR_CPU0_AP26  POWER  = PVDDCR_CPU0_P0
  AP27  VDDCR_CPU0_AP27  POWER  = PVDDCR_CPU0_P0
  AP28  VSS_AP28  POWER  = GND
  AP29  VDDCR_CPU0_AP29  POWER  = PVDDCR_CPU0_P0
  AP30  VDDCR_CPU0_AP30  POWER  = PVDDCR_CPU0_P0
  AP31  VSS_AP31  POWER  = GND
  AP32  VDDCR_CPU0_AP32  POWER  = PVDDCR_CPU0_P0
  AP33  VDDCR_CPU0_AP33  POWER  = PVDDCR_CPU0_P0
  AP34  VSS_AP34  POWER  = GND
  AP35  \g3_rxn15||sata37_rxn\  IN  = P5E_CPU0_G3_RX_DN<15>
  AP36  \g3_rxp15||sata37_rxp\  IN  = P5E_CPU0_G3_RX_DP<15>
  AP37  VSS_AP37  POWER  = GND
  AP39  VSS_AP39  POWER  = GND
  AP40  G1_TXP0  OUT  = GMI_CPU0_G1_CPU1_G3_TX_DP<0>
  AP41  G1_TXN0  OUT  = GMI_CPU0_G1_CPU1_G3_TX_DN<0>
  AP42  VSS_AP42  POWER  = GND
  AP43  VDDCR_CPU0_AP43  POWER  = PVDDCR_CPU0_P0
  AP44  VDDCR_CPU0_AP44  POWER  = PVDDCR_CPU0_P0
  AP45  VSS_AP45  POWER  = GND
  AP46  VDDCR_CPU0_AP46  POWER  = PVDDCR_CPU0_P0
  AP47  VDDCR_CPU0_AP47  POWER  = PVDDCR_CPU0_P0
  AP48  VSS_AP48  POWER  = GND
  AP49  VDDCR_CPU0_AP49  POWER  = PVDDCR_CPU0_P0
  AP50  VDDCR_CPU0_AP50  POWER  = PVDDCR_CPU0_P0
  AP51  VSS_AP51  POWER  = GND
  AP52  VDDCR_CPU0_AP52  POWER  = PVDDCR_CPU0_P0
  AP53  VDDCR_CPU0_AP53  POWER  = PVDDCR_CPU0_P0
  AP54  VSS_AP54  POWER  = GND
  AP55  MCA_CHECK5  BI  = M_C_CPU0_SA_CB<5>
  AP56  MCA_CHECK6  BI  = M_C_CPU0_SA_CB<6>
  AP57  VSS_AP57  POWER  = GND
  AP58  MDA_CHECK5  BI  = M_D_CPU0_SA_CB<5>
  AP59  VSS_AP59  POWER  = GND
  AP60  MDA_CHECK6  BI  = M_D_CPU0_SA_CB<6>
  AP61  VSS_AP61  POWER  = GND
  AP62  MBA_CHECK5  BI  = M_B_CPU0_SA_CB<5>
  AP63  MBA_CHECK6  BI  = M_B_CPU0_SA_CB<6>
  AP64  VSS_AP64  POWER  = GND
  AP65  MFA_CHECK5  BI  = M_F_CPU0_SA_CB<5>
  AP66  VSS_AP66  POWER  = GND
  AP67  MFA_CHECK6  BI  = M_F_CPU0_SA_CB<6>
  AP68  VSS_AP68  POWER  = GND
  AP69  MEA_CHECK5  BI  = M_E_CPU0_SA_CB<5>
  AP70  MEA_CHECK6  BI  = M_E_CPU0_SA_CB<6>
  AP71  VSS_AP71  POWER  = GND
  AP72  MAA_CHECK5  BI  = M_A_CPU0_SA_CB<5>
  AP73  VSS_AP73  POWER  = GND
  AP74  MAA_CHECK6  BI  = M_A_CPU0_SA_CB<6>
  AR1  VSS_AR1  POWER  = GND
  AR2  MG_ALERT_L  IN  = M_G_CPU0_ALERT_R_N
  AR3  MGA_CHECK7  BI  = M_G_CPU0_SA_CB<7>
  AR4  VDDCR_SOC_AR4  POWER  = PVDDCR_SOC_P0
  AR5  VSS_AR5  POWER  = GND
  AR6  VSS_AR6  POWER  = GND
  AR7  MKA_CHECK7  BI  = M_K_CPU0_SA_CB<7>
  AR8  VSS_AR8  POWER  = GND
  AR9  VSS_AR9  POWER  = GND
  AR10  MLA_CHECK7  BI  = M_L_CPU0_SA_CB<7>
  AR11  VDDCR_SOC_AR11  POWER  = PVDDCR_SOC_P0
  AR12  VSS_AR12  POWER  = GND
  AR13  VSS_AR13  POWER  = GND
  AR14  MHA_CHECK7  BI  = M_H_CPU0_SA_CB<7>
  AR15  VSS_AR15  POWER  = GND
  AR16  VSS_AR16  POWER  = GND
  AR17  MJA_CHECK7  BI  = M_J_CPU0_SA_CB<7>
  AR18  VDDCR_SOC_AR18  POWER  = PVDDCR_SOC_P0
  AR19  VSS_AR19  POWER  = GND
  AR20  VSS_AR20  POWER  = GND
  AR21  MIA_CHECK7  BI  = M_I_CPU0_SA_CB<7>
  AR22  VSS_AR22  POWER  = GND
  AR23  VDDCR_CPU0_AR23  POWER  = PVDDCR_CPU0_P0
  AR24  VSS_AR24  POWER  = GND
  AR25  VDDCR_CPU0_AR25  POWER  = PVDDCR_CPU0_P0
  AR26  VSS_AR26  POWER  = GND
  AR27  VDDCR_CPU0_AR27  POWER  = PVDDCR_CPU0_P0
  AR28  VSS_AR28  POWER  = GND
  AR29  VDDCR_CPU0_AR29  POWER  = PVDDCR_CPU0_P0
  AR30  VSS_AR30  POWER  = GND
  AR31  VDDCR_CPU0_AR31  POWER  = PVDDCR_CPU0_P0
  AR32  VSS_AR32  POWER  = GND
  AR33  VDDCR_CPU0_AR33  POWER  = PVDDCR_CPU0_P0
  AR34  VSS_AR34  POWER  = GND
  AR35  VDDCR_CPU0_AR35  POWER  = PVDDCR_CPU0_P0
  AR36  VSS_AR36  POWER  = GND
  AR40  VDDCR_CPU0_AR40  POWER  = PVDDCR_CPU0_P0
  AR41  VSS_AR41  POWER  = GND
  AR42  VDDCR_CPU0_AR42  POWER  = PVDDCR_CPU0_P0
  AR43  VSS_AR43  POWER  = GND
  AR44  VDDCR_CPU0_AR44  POWER  = PVDDCR_CPU0_P0
  AR45  VSS_AR45  POWER  = GND
  AR46  VDDCR_CPU0_AR46  POWER  = PVDDCR_CPU0_P0
  AR47  VSS_AR47  POWER  = GND
  AR48  VDDCR_CPU0_AR48  POWER  = PVDDCR_CPU0_P0
  AR49  VSS_AR49  POWER  = GND
  AR50  VDDCR_CPU0_AR50  POWER  = PVDDCR_CPU0_P0
  AR51  VSS_AR51  POWER  = GND
  AR52  VDD_18_S5_AR52  POWER  = PVDD18_S5_P0
  AR53  VSS_AR53  POWER  = GND
  AR54  VDD_18_S5_AR54  POWER  = PVDD18_S5_P0
  AR55  MCA_CHECK7  BI  = M_C_CPU0_SA_CB<7>
  AR56  VSS_AR56  POWER  = GND
  AR57  VSS_AR57  POWER  = GND
  AR58  VDDIO_AR58  POWER  = PVDDIO_P0
  AR59  MDA_CHECK7  BI  = M_D_CPU0_SA_CB<7>
  AR60  VSS_AR60  POWER  = GND
  AR61  VSS_AR61  POWER  = GND
  AR62  MBA_CHECK7  BI  = M_B_CPU0_SA_CB<7>
  AR63  VSS_AR63  POWER  = GND
  AR64  VSS_AR64  POWER  = GND
  AR65  VDDIO_AR65  POWER  = PVDDIO_P0
  AR66  MFA_CHECK7  BI  = M_F_CPU0_SA_CB<7>
  AR67  VSS_AR67  POWER  = GND
  AR68  VSS_AR68  POWER  = GND
  AR69  MEA_CHECK7  BI  = M_E_CPU0_SA_CB<7>
  AR70  VSS_AR70  POWER  = GND
  AR71  VSS_AR71  POWER  = GND
  AR72  VDDIO_AR72  POWER  = PVDDIO_P0
  AR73  MAA_CHECK7  BI  = M_A_CPU0_SA_CB<7>
  AR74  MA_ALERT_L  IN  = M_A_CPU0_ALERT_R_N
  AR75  VSS_AR75  POWER  = GND
  AT2  MG_RESET_L  OUT  = M_G_CPU0_RESET_N
  AT3  VSS_AT3  POWER  = GND
  AT4  VSS_AT4  POWER  = GND
  AT5  VSS_AT5  POWER  = GND
  AT6  VSS_AT6  POWER  = GND
  AT7  MK_ALERT_L  IN  = M_K_CPU0_ALERT_R_N
  AT8  VSS_AT8  POWER  = GND
  AT9  VSS_AT9  POWER  = GND
  AT10  VSS_AT10  POWER  = GND
  AT11  ML_ALERT_L  IN  = M_L_CPU0_ALERT_R_N
  AT12  VSS_AT12  POWER  = GND
  AT13  VSS_AT13  POWER  = GND
  AT14  MH_ALERT_L  IN  = M_H_CPU0_ALERT_R_N
  AT15  VSS_AT15  POWER  = GND
  AT16  VSS_AT16  POWER  = GND
  AT17  VSS_AT17  POWER  = GND
  AT18  MJ_ALERT_L  IN  = M_J_CPU0_ALERT_R_N
  AT19  VSS_AT19  POWER  = GND
  AT20  VSS_AT20  POWER  = GND
  AT21  MI_ALERT_L  IN  = M_I_CPU0_ALERT_R_N
  AT22  VDDCR_SOC_AT22  POWER  = PVDDCR_SOC_P0
  AT23  VSS_AT23  POWER  = GND
  AT24  VDDCR_CPU0_AT24  POWER  = PVDDCR_CPU0_P0
  AT25  VSS_AT25  POWER  = GND
  AT26  VDDCR_CPU0_AT26  POWER  = PVDDCR_CPU0_P0
  AT27  VSS_AT27  POWER  = GND
  AT28  VDDCR_CPU0_AT28  POWER  = PVDDCR_CPU0_P0
  AT29  VSS_AT29  POWER  = GND
  AT30  VDDCR_CPU0_AT30  POWER  = PVDDCR_CPU0_P0
  AT31  VSS_AT31  POWER  = GND
  AT32  VDDCR_CPU0_AT32  POWER  = PVDDCR_CPU0_P0
  AT33  VSS_AT33  POWER  = GND
  AT34  VDDCR_CPU0_AT34  POWER  = PVDDCR_CPU0_P0
  AT35  VSS_AT35  POWER  = GND
  AT36  VDDCR_CPU0_AT36  POWER  = PVDDCR_CPU0_P0
  AT37  VSS_AT37  POWER  = GND
  AT39  VDDCR_CPU0_AT39  POWER  = PVDDCR_CPU0_P0
  AT40  VSS_AT40  POWER  = GND
  AT41  VDDCR_CPU0_AT41  POWER  = PVDDCR_CPU0_P0
  AT42  VSS_AT42  POWER  = GND
  AT43  VDDCR_CPU0_AT43  POWER  = PVDDCR_CPU0_P0
  AT44  VSS_AT44  POWER  = GND
  AT45  VDDCR_CPU0_AT45  POWER  = PVDDCR_CPU0_P0
  AT46  VSS_AT46  POWER  = GND
  AT47  VDDCR_CPU0_AT47  POWER  = PVDDCR_CPU0_P0
  AT48  VSS_AT48  POWER  = GND
  AT49  VDDCR_CPU0_AT49  POWER  = PVDDCR_CPU0_P0
  AT50  VSS_AT50  POWER  = GND
  AT51  VDD_18_S5_AT51  POWER  = PVDD18_S5_P0
  AT52  VSS_AT52  POWER  = GND
  AT53  VDD_18_S5_AT53  POWER  = PVDD18_S5_P0
  AT54  VSS_AT54  POWER  = GND
  AT55  MC_ALERT_L  IN  = M_C_CPU0_ALERT_R_N
  AT56  VSS_AT56  POWER  = GND
  AT57  VSS_AT57  POWER  = GND
  AT58  MD_ALERT_L  IN  = M_D_CPU0_ALERT_R_N
  AT59  VSS_AT59  POWER  = GND
  AT60  VSS_AT60  POWER  = GND
  AT61  VSS_AT61  POWER  = GND
  AT62  MB_ALERT_L  IN  = M_B_CPU0_ALERT_R_N
  AT63  VSS_AT63  POWER  = GND
  AT64  VSS_AT64  POWER  = GND
  AT65  MF_ALERT_L  IN  = M_F_CPU0_ALERT_R_N
  AT66  VSS_AT66  POWER  = GND
  AT67  VSS_AT67  POWER  = GND
  AT68  VSS_AT68  POWER  = GND
  AT69  ME_ALERT_L  IN  = M_E_CPU0_ALERT_R_N
  AT70  VSS_AT70  POWER  = GND
  AT71  VSS_AT71  POWER  = GND
  AT72  VSS_AT72  POWER  = GND
  AT73  VSS_AT73  POWER  = GND
  AT74  MA_RESET_L  OUT  = M_A_CPU0_RESET_N
  AU1  VSS_AU1  POWER  = GND
  AU2  MGA0_CS_L0  OUT  = M_G_CPU0_SA_CS_N<0>
  AU3  VSS_AU3  POWER  = GND
  AU4  VSS_AU4  POWER  = GND
  AU5  MKA0_CS_L0  OUT  = M_K_CPU0_SA_CS_N<0>
  AU6  VSS_AU6  POWER  = GND
  AU7  MK_RESET_L  OUT  = M_K_CPU0_RESET_N
  AU8  VSS_AU8  POWER  = GND
  AU9  MLA0_CS_L0  OUT  = M_L_CPU0_SA_CS_N<0>
  AU10  ML_RESET_L  OUT  = M_L_CPU0_RESET_N
  AU11  VSS_AU11  POWER  = GND
  AU12  MHA0_CS_L0  OUT  = M_H_CPU0_SA_CS_N<0>
  AU13  VSS_AU13  POWER  = GND
  AU14  MH_RESET_L  OUT  = M_H_CPU0_RESET_N
  AU15  VSS_AU15  POWER  = GND
  AU16  MJA0_CS_L0  OUT  = M_J_CPU0_SA_CS_N<0>
  AU17  MJ_RESET_L  OUT  = M_J_CPU0_RESET_N
  AU18  VSS_AU18  POWER  = GND
  AU19  MIA0_CS_L0  OUT  = M_I_CPU0_SA_CS_N<0>
  AU20  VSS_AU20  POWER  = GND
  AU21  MI_RESET_L  OUT  = M_I_CPU0_RESET_N
  AU22  VSS_AU22  POWER  = GND
  AU23  VDDCR_SOC_AU23  POWER  = PVDDCR_SOC_P0
  AU24  VSS_AU24  POWER  = GND
  AU25  VDDCR_CPU0_AU25  POWER  = PVDDCR_CPU0_P0
  AU26  VSS_AU26  POWER  = GND
  AU27  VDDCR_SOC_AU27  POWER  = PVDDCR_SOC_P0
  AU28  VSS_AU28  POWER  = GND
  AU29  VDDCR_CPU0_AU29  POWER  = PVDDCR_CPU0_P0
  AU30  VSS_AU30  POWER  = GND
  AU31  VDDCR_SOC_AU31  POWER  = PVDDCR_SOC_P0
  AU32  VSS_AU32  POWER  = GND
  AU33  VDDCR_CPU0_AU33  POWER  = PVDDCR_CPU0_P0
  AU34  VSS_AU34  POWER  = GND
  AU35  VDDCR_SOC_AU35  POWER  = PVDDCR_SOC_P0
  AU36  VSS_AU36  POWER  = GND
  AU40  VDDCR_SOC_AU40  POWER  = PVDDCR_SOC_P0
  AU41  VSS_AU41  POWER  = GND
  AU42  VDDCR_CPU0_AU42  POWER  = PVDDCR_CPU0_P0
  AU43  VSS_AU43  POWER  = GND
  AU44  VDDCR_CPU0_AU44  POWER  = PVDDCR_CPU0_P0
  AU45  VSS_AU45  POWER  = GND
  AU46  VDDCR_CPU0_AU46  POWER  = PVDDCR_CPU0_P0
  AU47  VSS_AU47  POWER  = GND
  AU48  VDDCR_CPU0_AU48  POWER  = PVDDCR_CPU0_P0
  AU49  VSS_AU49  POWER  = GND
  AU50  VDD_18_S5_AU50  POWER  = PVDD18_S5_P0
  AU51  VSS_AU51  POWER  = GND
  AU52  VDD_18_S5_AU52  POWER  = PVDD18_S5_P0
  AU53  VSS_AU53  POWER  = GND
  AU54  VDD_18_S5_AU54  POWER  = PVDD18_S5_P0
  AU55  MC_RESET_L  OUT  = M_C_CPU0_RESET_N
  AU56  VSS_AU56  POWER  = GND
  AU57  MCA1_CS_L0  OUT  = NC
  AU58  VSS_AU58  POWER  = GND
  AU59  MD_RESET_L  OUT  = M_D_CPU0_RESET_N
  AU60  MDA1_CS_L0  OUT  = NC
  AU61  VSS_AU61  POWER  = GND
  AU62  MB_RESET_L  OUT  = M_B_CPU0_RESET_N
  AU63  VSS_AU63  POWER  = GND
  AU64  MBA1_CS_L0  OUT  = NC
  AU65  VSS_AU65  POWER  = GND
  AU66  MF_RESET_L  OUT  = M_F_CPU0_RESET_N
  AU67  MFA1_CS_L0  OUT  = NC
  AU68  VSS_AU68  POWER  = GND
  AU69  ME_RESET_L  OUT  = M_E_CPU0_RESET_N
  AU70  VSS_AU70  POWER  = GND
  AU71  MEA1_CS_L0  OUT  = NC
  AU72  VSS_AU72  POWER  = GND
  AU73  VSS_AU73  POWER  = GND
  AU74  MAA1_CS_L0  OUT  = NC
  AU75  VSS_AU75  POWER  = GND
  AV2  MGA1_CS_L0  OUT  = NC
  AV3  VSS_AV3  POWER  = GND
  AV4  MGA0_CS_L1  OUT  = M_G_CPU0_SA_CS_N<1>
  AV5  VDDCR_SOC_AV5  POWER  = PVDDCR_SOC_P0
  AV6  MKA1_CS_L0  OUT  = NC
  AV7  MKA0_CS_L1  OUT  = M_K_CPU0_SA_CS_N<1>
  AV8  VSS_AV8  POWER  = GND
  AV9  MLA1_CS_L0  OUT  = NC
  AV10  VSS_AV10  POWER  = GND
  AV11  MLA0_CS_L1  OUT  = M_L_CPU0_SA_CS_N<1>
  AV12  VDDCR_SOC_AV12  POWER  = PVDDCR_SOC_P0
  AV13  MHA1_CS_L0  OUT  = NC
  AV14  MHA0_CS_L1  OUT  = M_H_CPU0_SA_CS_N<1>
  AV15  VSS_AV15  POWER  = GND
  AV16  MJA1_CS_L0  OUT  = NC
  AV17  VSS_AV17  POWER  = GND
  AV18  MJA0_CS_L1  OUT  = M_J_CPU0_SA_CS_N<1>
  AV19  VDDCR_SOC_AV19  POWER  = PVDDCR_SOC_P0
  AV20  MIA1_CS_L0  OUT  = NC
  AV21  MIA0_CS_L1  OUT  = M_I_CPU0_SA_CS_N<1>
  AV22  VDDCR_SOC_AV22  POWER  = PVDDCR_SOC_P0
  AV23  VSS_AV23  POWER  = GND
  AV24  VDDCR_SOC_AV24  POWER  = PVDDCR_SOC_P0
  AV25  VSS_AV25  POWER  = GND
  AV26  VDDCR_SOC_AV26  POWER  = PVDDCR_SOC_P0
  AV27  VSS_AV27  POWER  = GND
  AV28  VDDCR_SOC_AV28  POWER  = PVDDCR_SOC_P0
  AV29  VSS_AV29  POWER  = GND
  AV30  VDDCR_SOC_AV30  POWER  = PVDDCR_SOC_P0
  AV31  VSS_AV31  POWER  = GND
  AV32  VDDCR_SOC_AV32  POWER  = PVDDCR_SOC_P0
  AV33  VSS_AV33  POWER  = GND
  AV34  VDDCR_SOC_AV34  POWER  = PVDDCR_SOC_P0
  AV35  VSS_AV35  POWER  = GND
  AV36  VDDCR_SOC_AV36  POWER  = PVDDCR_SOC_P0
  AV37  VSS_AV37  POWER  = GND
  AV39  VDDCR_SOC_AV39  POWER  = PVDDCR_SOC_P0
  AV40  VSS_AV40  POWER  = GND
  AV41  VDDCR_SOC_AV41  POWER  = PVDDCR_SOC_P0
  AV42  VSS_AV42  POWER  = GND
  AV43  VDDCR_SOC_AV43  POWER  = PVDDCR_SOC_P0
  AV44  VSS_AV44  POWER  = GND
  AV45  VDDCR_SOC_AV45  POWER  = PVDDCR_SOC_P0
  AV46  VSS_AV46  POWER  = GND
  AV47  VDDCR_SOC_AV47  POWER  = PVDDCR_SOC_P0
  AV48  VSS_AV48  POWER  = GND
  AV49  VDD_18_S5_AV49  POWER  = PVDD18_S5_P0
  AV50  VSS_AV50  POWER  = GND
  AV51  VDD_18_S5_AV51  POWER  = PVDD18_S5_P0
  AV52  VSS_AV52  POWER  = GND
  AV53  VDD_18_S5_AV53  POWER  = PVDD18_S5_P0
  AV54  VSS_AV54  POWER  = GND
  AV55  MCA1_CS_L1  OUT  = NC
  AV56  MCA0_CS_L0  OUT  = M_C_CPU0_SA_CS_N<0>
  AV57  VDDIO_AV57  POWER  = PVDDIO_P0
  AV58  MDA1_CS_L1  OUT  = NC
  AV59  VSS_AV59  POWER  = GND
  AV60  MDA0_CS_L0  OUT  = M_D_CPU0_SA_CS_N<0>
  AV61  VSS_AV61  POWER  = GND
  AV62  MBA1_CS_L1  OUT  = NC
  AV63  MBA0_CS_L0  OUT  = M_B_CPU0_SA_CS_N<0>
  AV64  VDDIO_AV64  POWER  = PVDDIO_P0
  AV65  MFA1_CS_L1  OUT  = NC
  AV66  VSS_AV66  POWER  = GND
